FILE_TYPE = CONNECTIVITY;
{Allegro Design Entry HDL 16.6-p007 (v16-6-112F) 10/10/2012}
"PAGE_NUMBER" = 248;
0"NC";
END.
